# S9S_MB_2U (Grand Teton) — schematic netlist excerpt (pin names and nets, part order shuffled) for the footprints in the layout excerpt that follows; sources: Cadence DE-HDL packaged netlist, KiCad conversion of 03242023_DA0F0TMBIJ0_F0T_Motherboard_J_brd_V01_OCP.brd

R2554  Q_RES  49.9 1% CHIP  pkg 0402LF  page 284 : A = SVID_CLK0_CPU1_R ; B = PVNN_TERM_CPU1
C321  Q_CAP  47UF 4V 20% X6S  pkg C0805  page 78 : A = PVCCIN_CPU1 ; B = GND
R1391  Q_RES  240 1% EMPTY  pkg 0402LF  page 120 : A = GND ; B = FM_S3M_CPU0_LVC1_GPIO_2

(kicad_pcb
	(version 20260206)
	(generator "pcbnew")
	(generator_version "10.0")
	(general
		(thickness 1.6)
		(legacy_teardrops no)
	)
	(paper "A4")
	(title_block
		(title "03242023_DA0F0TMBIJ0_F0T_Motherboard_J_brd_V01_OCP.brd")
		(comment 1 "Grand Teton / footprints 4409-4411 of 6105")
	)
	(layers
		(0 "F.Cu" signal "TOP")
		(4 "In1.Cu" signal "GND")
		(6 "In2.Cu" signal "IN1")
		(8 "In3.Cu" signal "GND1")
		(10 "In4.Cu" signal "IN2")
		(12 "In5.Cu" signal "GND2")
		(14 "In6.Cu" signal "IN3")
		(16 "In7.Cu" signal "GND3")
		(18 "In8.Cu" signal "VCC")
		(20 "In9.Cu" signal "VCC1")
		(22 "In10.Cu" signal "GND4")
		(24 "In11.Cu" signal "IN4")
		(26 "In12.Cu" signal "GND5")
		(28 "In13.Cu" signal "IN5")
		(30 "In14.Cu" signal "GND6")
		(32 "In15.Cu" signal "IN6")
		(34 "In16.Cu" signal "GND7")
		(2 "B.Cu" signal "BOTTOM")
		(9 "F.Adhes" user "F.Adhesive")
		(11 "B.Adhes" user "B.Adhesive")
		(13 "F.Paste" user "Package Geometry/Pastemask Top")
		(15 "B.Paste" user "Package Geometry/Pastemask Bottom")
		(5 "F.SilkS" user "Ref Des/Silkscreen Top")
		(7 "B.SilkS" user "Ref Des/Silkscreen Bottom")
		(1 "F.Mask" user "Board Geometry/Soldermask Top")
		(3 "B.Mask" user "Board Geometry/Soldermask Bottom")
		(17 "Dwgs.User" user "User.Drawings")
		(19 "Cmts.User" user "User.Comments")
		(21 "Eco1.User" user "User.Eco1")
		(23 "Eco2.User" user "User.Eco2")
		(25 "Edge.Cuts" user "Board Geometry/Outline")
		(27 "Margin" user)
		(31 "F.CrtYd" user "Package Geometry/Place Bound Top")
		(29 "B.CrtYd" user "Package Geometry/Place Bound Bottom")
		(35 "F.Fab" user "Ref Des/Assembly Top")
		(33 "B.Fab" user "Ref Des/Assembly Bottom")
	)
	(footprint ""
		(layer "B.Cu")
		(at 100.306886 -357.53167)
		(property "Reference" "R2554"
			(at 0 0 0)
			(layer "B.SilkS")
			(hide yes)
			(effects
				(font
					(size 1.27 1.27)
				)
				(justify mirror)
			)
		)
		(property "Value" ""
			(at 0 0 0)
			(layer "B.Fab")
			(effects
				(font
					(size 1.27 1.27)
				)
				(justify mirror)
			)
		)
		(duplicate_pad_numbers_are_jumpers no)
		(fp_line
			(start -0.7874 -0.4064)
			(end -0.7874 0.4064)
			(stroke
				(width 0.1524)
				(type default)
			)
			(layer "B.SilkS")
		)
		(fp_line
			(start -0.7874 0.4064)
			(end 0.7874 0.4064)
			(stroke
				(width 0.1524)
				(type default)
			)
			(layer "B.SilkS")
		)
		(fp_line
			(start 0.7874 -0.4064)
			(end -0.7874 -0.4064)
			(stroke
				(width 0.1524)
				(type default)
			)
			(layer "B.SilkS")
		)
		(fp_line
			(start 0.7874 0.4064)
			(end 0.7874 -0.4064)
			(stroke
				(width 0.1524)
				(type default)
			)
			(layer "B.SilkS")
		)
		(fp_line
			(start -0.67945 -0.3048)
			(end -0.67945 0.3048)
			(stroke
				(width 0.1)
				(type default)
			)
			(layer "B.Fab")
		)
		(fp_line
			(start -0.67945 0.3048)
			(end -0.120396 0.3048)
			(stroke
				(width 0.1)
				(type default)
			)
			(layer "B.Fab")
		)
		(fp_line
			(start -0.12065 -0.3048)
			(end -0.67945 -0.3048)
			(stroke
				(width 0.1)
				(type default)
			)
			(layer "B.Fab")
		)
		(fp_line
			(start -0.12065 -0.2794)
			(end -0.12065 -0.3048)
			(stroke
				(width 0.1)
				(type default)
			)
			(layer "B.Fab")
		)
		(fp_line
			(start -0.120396 0.2794)
			(end 0.12065 0.2794)
			(stroke
				(width 0.1)
				(type default)
			)
			(layer "B.Fab")
		)
		(fp_line
			(start -0.120396 0.3048)
			(end -0.120396 0.2794)
			(stroke
				(width 0.1)
				(type default)
			)
			(layer "B.Fab")
		)
		(fp_line
			(start 0.12065 -0.305054)
			(end 0.12065 -0.2794)
			(stroke
				(width 0.1)
				(type default)
			)
			(layer "B.Fab")
		)
		(fp_line
			(start 0.12065 -0.2794)
			(end -0.12065 -0.2794)
			(stroke
				(width 0.1)
				(type default)
			)
			(layer "B.Fab")
		)
		(fp_line
			(start 0.12065 0.2794)
			(end 0.12065 0.3048)
			(stroke
				(width 0.1)
				(type default)
			)
			(layer "B.Fab")
		)
		(fp_line
			(start 0.12065 0.3048)
			(end 0.67945 0.3048)
			(stroke
				(width 0.1)
				(type default)
			)
			(layer "B.Fab")
		)
		(fp_line
			(start 0.67945 -0.305054)
			(end 0.12065 -0.305054)
			(stroke
				(width 0.1)
				(type default)
			)
			(layer "B.Fab")
		)
		(fp_line
			(start 0.67945 0.3048)
			(end 0.67945 -0.305054)
			(stroke
				(width 0.1)
				(type default)
			)
			(layer "B.Fab")
		)
		(pad "1" smd circle
			(at 0.40005 0 180)
			(size 0 0)
			(layers "B.Cu" "B.Mask" "B.Paste")
			(net "SVID_CLK0_CPU1_R")
		)
		(pad "2" smd circle
			(at -0.40005 0 180)
			(size 0 0)
			(layers "B.Cu" "B.Mask" "B.Paste")
			(net "PVNN_TERM_CPU1")
		)
	)
	(footprint ""
		(layer "B.Cu")
		(at 279.119584 -193.669666 -90)
		(property "Reference" "R1391"
			(at 0 0 90)
			(layer "B.SilkS")
			(hide yes)
			(effects
				(font
					(size 1.27 1.27)
				)
				(justify mirror)
			)
		)
		(property "Value" ""
			(at 0 0 90)
			(layer "B.Fab")
			(effects
				(font
					(size 1.27 1.27)
				)
				(justify mirror)
			)
		)
		(duplicate_pad_numbers_are_jumpers no)
		(fp_line
			(start -0.7874 0.4064)
			(end 0.7874 0.4064)
			(stroke
				(width 0.1524)
				(type default)
			)
			(layer "B.SilkS")
		)
		(fp_line
			(start 0.7874 0.4064)
			(end 0.7874 -0.4064)
			(stroke
				(width 0.1524)
				(type default)
			)
			(layer "B.SilkS")
		)
		(fp_line
			(start -0.7874 -0.4064)
			(end -0.7874 0.4064)
			(stroke
				(width 0.1524)
				(type default)
			)
			(layer "B.SilkS")
		)
		(fp_line
			(start 0.7874 -0.4064)
			(end -0.7874 -0.4064)
			(stroke
				(width 0.1524)
				(type default)
			)
			(layer "B.SilkS")
		)
		(fp_line
			(start -0.67945 0.3048)
			(end -0.120396 0.3048)
			(stroke
				(width 0.1)
				(type default)
			)
			(layer "B.Fab")
		)
		(fp_line
			(start -0.120396 0.3048)
			(end -0.120396 0.2794)
			(stroke
				(width 0.1)
				(type default)
			)
			(layer "B.Fab")
		)
		(fp_line
			(start 0.12065 0.3048)
			(end 0.67945 0.3048)
			(stroke
				(width 0.1)
				(type default)
			)
			(layer "B.Fab")
		)
		(fp_line
			(start 0.67945 0.3048)
			(end 0.67945 -0.305054)
			(stroke
				(width 0.1)
				(type default)
			)
			(layer "B.Fab")
		)
		(fp_line
			(start -0.120396 0.2794)
			(end 0.12065 0.2794)
			(stroke
				(width 0.1)
				(type default)
			)
			(layer "B.Fab")
		)
		(fp_line
			(start 0.12065 0.2794)
			(end 0.12065 0.3048)
			(stroke
				(width 0.1)
				(type default)
			)
			(layer "B.Fab")
		)
		(fp_line
			(start -0.12065 -0.2794)
			(end -0.12065 -0.3048)
			(stroke
				(width 0.1)
				(type default)
			)
			(layer "B.Fab")
		)
		(fp_line
			(start 0.12065 -0.2794)
			(end -0.12065 -0.2794)
			(stroke
				(width 0.1)
				(type default)
			)
			(layer "B.Fab")
		)
		(fp_line
			(start -0.67945 -0.3048)
			(end -0.67945 0.3048)
			(stroke
				(width 0.1)
				(type default)
			)
			(layer "B.Fab")
		)
		(fp_line
			(start -0.12065 -0.3048)
			(end -0.67945 -0.3048)
			(stroke
				(width 0.1)
				(type default)
			)
			(layer "B.Fab")
		)
		(fp_line
			(start 0.12065 -0.305054)
			(end 0.12065 -0.2794)
			(stroke
				(width 0.1)
				(type default)
			)
			(layer "B.Fab")
		)
		(fp_line
			(start 0.67945 -0.305054)
			(end 0.12065 -0.305054)
			(stroke
				(width 0.1)
				(type default)
			)
			(layer "B.Fab")
		)
		(pad "1" smd circle
			(at 0.40005 0 90)
			(size 0 0)
			(layers "B.Cu" "B.Mask" "B.Paste")
			(net "GND")
		)
		(pad "2" smd circle
			(at -0.40005 0 90)
			(size 0 0)
			(layers "B.Cu" "B.Mask" "B.Paste")
			(net "FM_S3M_CPU0_LVC1_GPIO_2")
		)
	)
	(footprint ""
		(layer "B.Cu")
		(at 105.679494 -255.8542 -90)
		(property "Reference" "C321"
			(at 0 0 90)
			(layer "B.SilkS")
			(hide yes)
			(effects
				(font
					(size 1.27 1.27)
				)
				(justify mirror)
			)
		)
		(property "Value" ""
			(at 0 0 90)
			(layer "B.Fab")
			(effects
				(font
					(size 1.27 1.27)
				)
				(justify mirror)
			)
		)
		(duplicate_pad_numbers_are_jumpers no)
		(fp_line
			(start -1.524 0.762)
			(end 1.524 0.762)
			(stroke
				(width 0.1524)
				(type default)
			)
			(layer "B.SilkS")
		)
		(fp_line
			(start 1.524 0.762)
			(end 1.524 -0.762)
			(stroke
				(width 0.1524)
				(type default)
			)
			(layer "B.SilkS")
		)
		(fp_line
			(start -1.524 -0.762)
			(end -1.524 0.762)
			(stroke
				(width 0.1524)
				(type default)
			)
			(layer "B.SilkS")
		)
		(fp_line
			(start 1.524 -0.762)
			(end -1.524 -0.762)
			(stroke
				(width 0.1524)
				(type default)
			)
			(layer "B.SilkS")
		)
		(fp_line
			(start -1.1049 0.724916)
			(end -1.1049 -0.724916)
			(stroke
				(width 0.1)
				(type default)
			)
			(layer "B.Fab")
		)
		(fp_line
			(start 1.1049 0.724916)
			(end -1.1049 0.724916)
			(stroke
				(width 0.1)
				(type default)
			)
			(layer "B.Fab")
		)
		(fp_line
			(start -1.1049 -0.724916)
			(end 1.1049 -0.724916)
			(stroke
				(width 0.1)
				(type default)
			)
			(layer "B.Fab")
		)
		(fp_line
			(start 1.1049 -0.724916)
			(end 1.1049 0.724916)
			(stroke
				(width 0.1)
				(type default)
			)
			(layer "B.Fab")
		)
		(pad "1" smd rect
			(at 0.889 0 270)
			(size 1.016 1.27)
			(layers "B.Cu" "B.Mask" "B.Paste")
			(net "PVCCIN_CPU1")
		)
		(pad "2" smd rect
			(at -0.889 0 270)
			(size 1.016 1.27)
			(layers "B.Cu" "B.Mask" "B.Paste")
			(net "GND")
		)
	)
)
